# T6G (Grand Teton) — schematic netlist excerpt (pin names and nets, part order shuffled) for the footprints in the layout excerpt that follows; sources: Cadence DE-HDL packaged netlist, KiCad conversion of 04192023_DAF0TMB3IC0_F0TG_MB_C_brd_V02_OCP.brd

R6701  Q_RES  0 5% EMPTY  pkg 0402LF  page 323 : A = P1V8_CPU1_RT_1D ; B = P1V8_CPU1_RT0_1A_1D
C54  Q_CAP_DIFFBUS  DIFF BUS_0.22UF 6.3V 20% X6S  pkg C0201  page 67 : \1\ = P5E_CPU1_P3_TX_C_DN<12> ; \2\ = P5E_CPU1_P3_TX_DN<12>
PR6554  Q_RES  5.6 1% CHIP  pkg 0402LF  page 363 : A = SW_P0V9_RETIMER_CPU0_BOOT1 ; B = SW_P0V9_RETIMER_CPU0_BOOT1_RC

(kicad_pcb
	(version 20260206)
	(generator "pcbnew")
	(generator_version "10.0")
	(general
		(thickness 1.6)
		(legacy_teardrops no)
	)
	(paper "A4")
	(title_block
		(title "04192023_DAF0TMB3IC0_F0TG_MB_C_brd_V02_OCP.brd")
		(comment 1 "Grand Teton / footprints 4343-4345 of 8354")
	)
	(layers
		(0 "F.Cu" signal "TOP")
		(4 "In1.Cu" signal "GND")
		(6 "In2.Cu" signal "IN1")
		(8 "In3.Cu" signal "GND1")
		(10 "In4.Cu" signal "IN2")
		(12 "In5.Cu" signal "GND2")
		(14 "In6.Cu" signal "IN3")
		(16 "In7.Cu" signal "GND3")
		(18 "In8.Cu" signal "VCC")
		(20 "In9.Cu" signal "VCC1")
		(22 "In10.Cu" signal "GND4")
		(24 "In11.Cu" signal "IN4")
		(26 "In12.Cu" signal "GND5")
		(28 "In13.Cu" signal "IN5")
		(30 "In14.Cu" signal "GND6")
		(32 "In15.Cu" signal "IN6")
		(34 "In16.Cu" signal "GND7")
		(2 "B.Cu" signal "BOTTOM")
		(9 "F.Adhes" user "F.Adhesive")
		(11 "B.Adhes" user "B.Adhesive")
		(13 "F.Paste" user "Package Geometry/Pastemask Top")
		(15 "B.Paste" user "Package Geometry/Pastemask Bottom")
		(5 "F.SilkS" user "Ref Des/Silkscreen Top")
		(7 "B.SilkS" user "Ref Des/Silkscreen Bottom")
		(1 "F.Mask" user "Board Geometry/Soldermask Top")
		(3 "B.Mask" user "Board Geometry/Soldermask Bottom")
		(17 "Dwgs.User" user "User.Drawings")
		(19 "Cmts.User" user "User.Comments")
		(21 "Eco1.User" user "User.Eco1")
		(23 "Eco2.User" user "User.Eco2")
		(25 "Edge.Cuts" user "Board Geometry/Outline")
		(27 "Margin" user)
		(31 "F.CrtYd" user "Package Geometry/Place Bound Top")
		(29 "B.CrtYd" user "Package Geometry/Place Bound Bottom")
		(35 "F.Fab" user "Ref Des/Assembly Top")
		(33 "B.Fab" user "Ref Des/Assembly Bottom")
	)
	(footprint ""
		(layer "F.Cu")
		(at 70.662546 -384.10388 180)
		(property "Reference" "R6701"
			(at 0 0 180)
			(layer "F.SilkS")
			(hide yes)
			(effects
				(font
					(size 1.27 1.27)
				)
			)
		)
		(property "Value" ""
			(at 0 0 180)
			(layer "F.Fab")
			(effects
				(font
					(size 1.27 1.27)
				)
			)
		)
		(duplicate_pad_numbers_are_jumpers no)
		(fp_line
			(start 0.7874 0.4064)
			(end -0.7874 0.4064)
			(stroke
				(width 0.1524)
				(type default)
			)
			(layer "F.SilkS")
		)
		(fp_line
			(start 0.7874 -0.4064)
			(end 0.7874 0.4064)
			(stroke
				(width 0.1524)
				(type default)
			)
			(layer "F.SilkS")
		)
		(fp_line
			(start -0.7874 0.4064)
			(end -0.7874 -0.4064)
			(stroke
				(width 0.1524)
				(type default)
			)
			(layer "F.SilkS")
		)
		(fp_line
			(start -0.7874 -0.4064)
			(end 0.7874 -0.4064)
			(stroke
				(width 0.1524)
				(type default)
			)
			(layer "F.SilkS")
		)
		(fp_line
			(start 0.67945 0.3048)
			(end 0.120396 0.3048)
			(stroke
				(width 0.1)
				(type default)
			)
			(layer "F.Fab")
		)
		(fp_line
			(start 0.67945 -0.3048)
			(end 0.67945 0.3048)
			(stroke
				(width 0.1)
				(type default)
			)
			(layer "F.Fab")
		)
		(fp_line
			(start 0.12065 -0.2794)
			(end 0.12065 -0.3048)
			(stroke
				(width 0.1)
				(type default)
			)
			(layer "F.Fab")
		)
		(fp_line
			(start 0.12065 -0.3048)
			(end 0.67945 -0.3048)
			(stroke
				(width 0.1)
				(type default)
			)
			(layer "F.Fab")
		)
		(fp_line
			(start 0.120396 0.3048)
			(end 0.120396 0.2794)
			(stroke
				(width 0.1)
				(type default)
			)
			(layer "F.Fab")
		)
		(fp_line
			(start 0.120396 0.2794)
			(end -0.12065 0.2794)
			(stroke
				(width 0.1)
				(type default)
			)
			(layer "F.Fab")
		)
		(fp_line
			(start -0.12065 0.3048)
			(end -0.67945 0.3048)
			(stroke
				(width 0.1)
				(type default)
			)
			(layer "F.Fab")
		)
		(fp_line
			(start -0.12065 0.2794)
			(end -0.12065 0.3048)
			(stroke
				(width 0.1)
				(type default)
			)
			(layer "F.Fab")
		)
		(fp_line
			(start -0.12065 -0.2794)
			(end 0.12065 -0.2794)
			(stroke
				(width 0.1)
				(type default)
			)
			(layer "F.Fab")
		)
		(fp_line
			(start -0.12065 -0.305054)
			(end -0.12065 -0.2794)
			(stroke
				(width 0.1)
				(type default)
			)
			(layer "F.Fab")
		)
		(fp_line
			(start -0.67945 0.3048)
			(end -0.67945 -0.305054)
			(stroke
				(width 0.1)
				(type default)
			)
			(layer "F.Fab")
		)
		(fp_line
			(start -0.67945 -0.305054)
			(end -0.12065 -0.305054)
			(stroke
				(width 0.1)
				(type default)
			)
			(layer "F.Fab")
		)
		(pad "1" smd rect
			(at -0.40005 0)
			(size 0.4572 0.508)
			(layers "F.Cu" "F.Mask" "F.Paste")
			(net "P1V8_CPU1_RT_1D")
		)
		(pad "2" smd rect
			(at 0.40005 0)
			(size 0.4572 0.508)
			(layers "F.Cu" "F.Mask" "F.Paste")
			(net "P1V8_CPU1_RT0_1A_1D")
		)
	)
	(footprint ""
		(layer "F.Cu")
		(at 446.036954 -401.785328 90)
		(property "Reference" "PR6554"
			(at 0 0 90)
			(layer "F.SilkS")
			(hide yes)
			(effects
				(font
					(size 1.27 1.27)
				)
			)
		)
		(property "Value" ""
			(at 0 0 90)
			(layer "F.Fab")
			(effects
				(font
					(size 1.27 1.27)
				)
			)
		)
		(duplicate_pad_numbers_are_jumpers no)
		(fp_line
			(start 0.7874 -0.4064)
			(end 0.7874 0.4064)
			(stroke
				(width 0.1524)
				(type default)
			)
			(layer "F.SilkS")
		)
		(fp_line
			(start -0.7874 -0.4064)
			(end 0.7874 -0.4064)
			(stroke
				(width 0.1524)
				(type default)
			)
			(layer "F.SilkS")
		)
		(fp_line
			(start 0.7874 0.4064)
			(end -0.7874 0.4064)
			(stroke
				(width 0.1524)
				(type default)
			)
			(layer "F.SilkS")
		)
		(fp_line
			(start -0.7874 0.4064)
			(end -0.7874 -0.4064)
			(stroke
				(width 0.1524)
				(type default)
			)
			(layer "F.SilkS")
		)
		(fp_line
			(start -0.12065 -0.305054)
			(end -0.12065 -0.2794)
			(stroke
				(width 0.1)
				(type default)
			)
			(layer "F.Fab")
		)
		(fp_line
			(start -0.67945 -0.305054)
			(end -0.12065 -0.305054)
			(stroke
				(width 0.1)
				(type default)
			)
			(layer "F.Fab")
		)
		(fp_line
			(start 0.67945 -0.3048)
			(end 0.67945 0.3048)
			(stroke
				(width 0.1)
				(type default)
			)
			(layer "F.Fab")
		)
		(fp_line
			(start 0.12065 -0.3048)
			(end 0.67945 -0.3048)
			(stroke
				(width 0.1)
				(type default)
			)
			(layer "F.Fab")
		)
		(fp_line
			(start 0.12065 -0.2794)
			(end 0.12065 -0.3048)
			(stroke
				(width 0.1)
				(type default)
			)
			(layer "F.Fab")
		)
		(fp_line
			(start -0.12065 -0.2794)
			(end 0.12065 -0.2794)
			(stroke
				(width 0.1)
				(type default)
			)
			(layer "F.Fab")
		)
		(fp_line
			(start 0.120396 0.2794)
			(end -0.12065 0.2794)
			(stroke
				(width 0.1)
				(type default)
			)
			(layer "F.Fab")
		)
		(fp_line
			(start -0.12065 0.2794)
			(end -0.12065 0.3048)
			(stroke
				(width 0.1)
				(type default)
			)
			(layer "F.Fab")
		)
		(fp_line
			(start 0.67945 0.3048)
			(end 0.120396 0.3048)
			(stroke
				(width 0.1)
				(type default)
			)
			(layer "F.Fab")
		)
		(fp_line
			(start 0.120396 0.3048)
			(end 0.120396 0.2794)
			(stroke
				(width 0.1)
				(type default)
			)
			(layer "F.Fab")
		)
		(fp_line
			(start -0.12065 0.3048)
			(end -0.67945 0.3048)
			(stroke
				(width 0.1)
				(type default)
			)
			(layer "F.Fab")
		)
		(fp_line
			(start -0.67945 0.3048)
			(end -0.67945 -0.305054)
			(stroke
				(width 0.1)
				(type default)
			)
			(layer "F.Fab")
		)
		(pad "1" smd circle
			(at -0.40005 0 90)
			(size 0 0)
			(layers "F.Cu" "F.Mask" "F.Paste")
			(net "SW_P0V9_RETIMER_CPU0_BOOT1")
		)
		(pad "2" smd circle
			(at 0.40005 0 90)
			(size 0 0)
			(layers "F.Cu" "F.Mask" "F.Paste")
			(net "SW_P0V9_RETIMER_CPU0_BOOT1_RC")
		)
	)
	(footprint ""
		(layer "F.Cu")
		(at 133.127496 -370.57203 -90)
		(property "Reference" "C54"
			(at 0 0 270)
			(layer "F.SilkS")
			(hide yes)
			(effects
				(font
					(size 1.27 1.27)
				)
			)
		)
		(property "Value" ""
			(at 0 0 270)
			(layer "F.Fab")
			(effects
				(font
					(size 1.27 1.27)
				)
			)
		)
		(duplicate_pad_numbers_are_jumpers no)
		(fp_line
			(start -0.299974 0.150114)
			(end -0.299974 -0.150114)
			(stroke
				(width 0.1)
				(type default)
			)
			(layer "F.Fab")
		)
		(fp_line
			(start 0.299974 0.150114)
			(end -0.299974 0.150114)
			(stroke
				(width 0.1)
				(type default)
			)
			(layer "F.Fab")
		)
		(fp_line
			(start -0.299974 -0.150114)
			(end 0.299974 -0.150114)
			(stroke
				(width 0.1)
				(type default)
			)
			(layer "F.Fab")
		)
		(fp_line
			(start 0.299974 -0.150114)
			(end 0.299974 0.150114)
			(stroke
				(width 0.1)
				(type default)
			)
			(layer "F.Fab")
		)
		(pad "1" smd rect
			(at -0.2667 0 270)
			(size 0.3048 0.381)
			(layers "F.Cu" "F.Mask" "F.Paste")
			(net "P5E_CPU1_P3_TX_C_DN<12>")
		)
		(pad "2" smd rect
			(at 0.2667 0 270)
			(size 0.3048 0.381)
			(layers "F.Cu" "F.Mask" "F.Paste")
			(net "P5E_CPU1_P3_TX_DN<12>")
		)
	)
)
